# BASEBOARD_FAB2 (Tioga Pass) — schematic netlist excerpt (pin names and nets, part order shuffled) for the footprints in the layout excerpt that follows; sources: Cadence DE-HDL packaged netlist, KiCad conversion of Wiwynn_Tioga_Pass_MB.brd

EU7B1  NCP3232L  IC  pkg SM  page 232
  SS  = VR_PVPP_DEF_SS
  FB  = VR_FB_PVPP_DEF
  COMP  = VR_COMP_PVPP_DEF_3
  ISET  = VR_PVPP_DEF_ISET
  AGND  = AGND_PVPP_DEF
  OTS  = AGND_PVPP_DEF
  PG  = PWRGD_PVPP_DEF_R
  VIN(0)  = VR_FET_SW_P12V_STBY_PVPP_DEF
  VIN(1)  = VR_FET_SW_P12V_STBY_PVPP_DEF
  VIN(2)  = VR_FET_SW_P12V_STBY_PVPP_DEF
  VIN(3)  = VR_FET_SW_P12V_STBY_PVPP_DEF
  VIN(4)  = VR_FET_SW_P12V_STBY_PVPP_DEF
  VIN(5)  = VR_FET_SW_P12V_STBY_PVPP_DEF
  VIN(6)  = VR_FET_SW_P12V_STBY_PVPP_DEF
  VSWH(0)  = VR_PVPP_DEF_PHASE
  PGND(0)  = GND
  PGND(1)  = GND
  PGND(2)  = GND
  PGND(3)  = GND
  PGND(4)  = GND
  PGND(5)  = GND
  PGND(6)  = GND
  PGND(7)  = GND
  PGND(8)  = GND
  PGND(9)  = GND
  PGND(10)  = GND
  PGND(11)  = GND
  PGND(12)  = GND
  VSWH(1)  = VR_PVPP_DEF_PHASE
  VSWH(2)  = VR_PVPP_DEF_PHASE
  VSWH(3)  = VR_PVPP_DEF_PHASE
  VSWH(4)  = VR_PVPP_DEF_PHASE
  VSWH(5)  = VR_PVPP_DEF_PHASE
  VSWH(6)  = VR_PVPP_DEF_PHASE
  VSW  = VR_PVPP_DEF_PHASE
  BST  = VR_PVPP_DEF_BOOT
  PGND(13)  = GND
  VB  = VR_VB_PVPP_DEF
  VCC  = VR_FET_SW_P12V_STBY_PVPP_DEF
  EN  = FM_PVPP_PVDDQ_CPU0_EN_DEF
  GND  = GND
  VIN(7)  = VR_FET_SW_P12V_STBY_PVPP_DEF
  VSWH(7)  = VR_PVPP_DEF_PHASE

(kicad_pcb
	(version 20260206)
	(generator "pcbnew")
	(generator_version "10.0")
	(general
		(thickness 1.6)
		(legacy_teardrops no)
	)
	(paper "A4")
	(title_block
		(title "Wiwynn_Tioga_Pass_MB.brd")
		(comment 1 "Tioga Pass / footprint 1728 of 4770 (EU7B1), pads 18-35 of 43")
	)
	(layers
		(0 "F.Cu" signal "TOP")
		(4 "In1.Cu" signal "L2GND")
		(6 "In2.Cu" signal "L3")
		(8 "In3.Cu" signal "L4GND")
		(10 "In4.Cu" signal "L5")
		(12 "In5.Cu" signal "L6GND")
		(14 "In6.Cu" signal "L7VCC")
		(16 "In7.Cu" signal "L8VCC")
		(18 "In8.Cu" signal "L9GND")
		(20 "In9.Cu" signal "L10")
		(22 "In10.Cu" signal "L11GND")
		(24 "In11.Cu" signal "L12")
		(26 "In12.Cu" signal "L13GND")
		(2 "B.Cu" signal "BOTTOM")
		(9 "F.Adhes" user "F.Adhesive")
		(11 "B.Adhes" user "B.Adhesive")
		(13 "F.Paste" user "Package Geometry/Pastemask Top")
		(15 "B.Paste" user "Package Geometry/Pastemask Bottom")
		(5 "F.SilkS" user "Ref Des/Silkscreen Top")
		(7 "B.SilkS" user "Ref Des/Silkscreen Bottom")
		(1 "F.Mask" user "Board Geometry/Soldermask Top")
		(3 "B.Mask" user "Board Geometry/Soldermask Bottom")
		(17 "Dwgs.User" user "User.Drawings")
		(19 "Cmts.User" user "User.Comments")
		(21 "Eco1.User" user "User.Eco1")
		(23 "Eco2.User" user "User.Eco2")
		(25 "Edge.Cuts" user "Board Geometry/Outline")
		(27 "Margin" user)
		(31 "F.CrtYd" user "Package Geometry/Place Bound Top")
		(29 "B.CrtYd" user "Package Geometry/Place Bound Bottom")
		(35 "F.Fab" user "Ref Des/Assembly Top")
		(33 "B.Fab" user "Ref Des/Assembly Bottom")
	)
	(footprint ""
		(layer "F.Cu")
		(at 344.043 -132.8547 90)
		(property "Reference" "EU7B1"
			(at 5.29463 -1.27 0)
			(unlocked yes)
			(layer "F.SilkS")
			(effects
				(font
					(size 0.7874 0.5842)
					(thickness 0.1524)
				)
				(justify left)
			)
		)
		(property "Value" ""
			(at 0 0 90)
			(layer "F.Fab")
			(effects
				(font
					(size 1.27 1.27)
				)
			)
		)
		(duplicate_pad_numbers_are_jumpers no)
		(pad "18" smd custom
			(at 1.249934 2.8321 90)
			(size 0.06985 0.06985)
			(layers "F.Cu" "F.Mask" "F.Paste")
			(net "GND")
			(options
				(clearance outline)
				(anchor circle)
			)
			(primitives
				(gr_poly
					(pts
						(arc
							(start -0.1397 -0.2413)
							(mid 0 -0.381)
							(end 0.1397 -0.2413)
						)
						(xy 0.1397 0.381) (xy -0.1397 0.381)
					)
					(width 0)
					(fill yes)
				)
			)
		)
		(pad "19" smd custom
			(at 1.75006 2.8321 90)
			(size 0.06985 0.06985)
			(layers "F.Cu" "F.Mask" "F.Paste")
			(net "GND")
			(options
				(clearance outline)
				(anchor circle)
			)
			(primitives
				(gr_poly
					(pts
						(arc
							(start -0.1397 -0.2413)
							(mid 0 -0.381)
							(end 0.1397 -0.2413)
						)
						(xy 0.1397 0.381) (xy -0.1397 0.381)
					)
					(width 0)
					(fill yes)
				)
			)
		)
		(pad "20" smd custom
			(at 2.249932 2.8321 90)
			(size 0.06985 0.06985)
			(layers "F.Cu" "F.Mask" "F.Paste")
			(net "GND")
			(options
				(clearance outline)
				(anchor circle)
			)
			(primitives
				(gr_poly
					(pts
						(arc
							(start -0.1397 -0.2413)
							(mid 0 -0.381)
							(end 0.1397 -0.2413)
						)
						(xy 0.1397 0.381) (xy -0.1397 0.381)
					)
					(width 0)
					(fill yes)
				)
			)
		)
		(pad "21" smd custom
			(at 2.8321 2.249932 90)
			(size 0.06985 0.06985)
			(layers "F.Cu" "F.Mask" "F.Paste")
			(net "GND")
			(options
				(clearance outline)
				(anchor circle)
			)
			(primitives
				(gr_poly
					(pts
						(arc
							(start -0.2413 0.1397)
							(mid -0.381 0)
							(end -0.2413 -0.1397)
						)
						(xy 0.381 -0.1397) (xy 0.381 0.1397)
					)
					(width 0)
					(fill yes)
				)
			)
		)
		(pad "22" smd custom
			(at 2.8321 1.75006 90)
			(size 0.06985 0.06985)
			(layers "F.Cu" "F.Mask" "F.Paste")
			(net "GND")
			(options
				(clearance outline)
				(anchor circle)
			)
			(primitives
				(gr_poly
					(pts
						(arc
							(start -0.2413 0.1397)
							(mid -0.381 0)
							(end -0.2413 -0.1397)
						)
						(xy 0.381 -0.1397) (xy 0.381 0.1397)
					)
					(width 0)
					(fill yes)
				)
			)
		)
		(pad "23" smd custom
			(at 2.8321 1.249934 90)
			(size 0.06985 0.06985)
			(layers "F.Cu" "F.Mask" "F.Paste")
			(net "GND")
			(options
				(clearance outline)
				(anchor circle)
			)
			(primitives
				(gr_poly
					(pts
						(arc
							(start -0.2413 0.1397)
							(mid -0.381 0)
							(end -0.2413 -0.1397)
						)
						(xy 0.381 -0.1397) (xy 0.381 0.1397)
					)
					(width 0)
					(fill yes)
				)
			)
		)
		(pad "24" smd custom
			(at 2.8321 0.750062 90)
			(size 0.06985 0.06985)
			(layers "F.Cu" "F.Mask" "F.Paste")
			(net "GND")
			(options
				(clearance outline)
				(anchor circle)
			)
			(primitives
				(gr_poly
					(pts
						(arc
							(start -0.2413 0.1397)
							(mid -0.381 0)
							(end -0.2413 -0.1397)
						)
						(xy 0.381 -0.1397) (xy 0.381 0.1397)
					)
					(width 0)
					(fill yes)
				)
			)
		)
		(pad "25" smd custom
			(at 2.8321 0.249936 90)
			(size 0.06985 0.06985)
			(layers "F.Cu" "F.Mask" "F.Paste")
			(net "GND")
			(options
				(clearance outline)
				(anchor circle)
			)
			(primitives
				(gr_poly
					(pts
						(arc
							(start -0.2413 0.1397)
							(mid -0.381 0)
							(end -0.2413 -0.1397)
						)
						(xy 0.381 -0.1397) (xy 0.381 0.1397)
					)
					(width 0)
					(fill yes)
				)
			)
		)
		(pad "26" smd custom
			(at 2.8321 -0.249936 90)
			(size 0.06985 0.06985)
			(layers "F.Cu" "F.Mask" "F.Paste")
			(net "GND")
			(options
				(clearance outline)
				(anchor circle)
			)
			(primitives
				(gr_poly
					(pts
						(arc
							(start -0.2413 0.1397)
							(mid -0.381 0)
							(end -0.2413 -0.1397)
						)
						(xy 0.381 -0.1397) (xy 0.381 0.1397)
					)
					(width 0)
					(fill yes)
				)
			)
		)
		(pad "27" smd custom
			(at 2.8321 -0.750062 90)
			(size 0.06985 0.06985)
			(layers "F.Cu" "F.Mask" "F.Paste")
			(net "GND")
			(options
				(clearance outline)
				(anchor circle)
			)
			(primitives
				(gr_poly
					(pts
						(arc
							(start -0.2413 0.1397)
							(mid -0.381 0)
							(end -0.2413 -0.1397)
						)
						(xy 0.381 -0.1397) (xy 0.381 0.1397)
					)
					(width 0)
					(fill yes)
				)
			)
		)
		(pad "28" smd custom
			(at 2.8321 -1.249934 90)
			(size 0.06985 0.06985)
			(layers "F.Cu" "F.Mask" "F.Paste")
			(net "GND")
			(options
				(clearance outline)
				(anchor circle)
			)
			(primitives
				(gr_poly
					(pts
						(arc
							(start -0.2413 0.1397)
							(mid -0.381 0)
							(end -0.2413 -0.1397)
						)
						(xy 0.381 -0.1397) (xy 0.381 0.1397)
					)
					(width 0)
					(fill yes)
				)
			)
		)
		(pad "29" smd custom
			(at 2.8321 -1.75006 90)
			(size 0.06985 0.06985)
			(layers "F.Cu" "F.Mask" "F.Paste")
			(net "VR_PVPP_DEF_PHASE")
			(options
				(clearance outline)
				(anchor circle)
			)
			(primitives
				(gr_poly
					(pts
						(arc
							(start -0.2413 0.1397)
							(mid -0.381 0)
							(end -0.2413 -0.1397)
						)
						(xy 0.381 -0.1397) (xy 0.381 0.1397)
					)
					(width 0)
					(fill yes)
				)
			)
		)
		(pad "30" smd custom
			(at 2.8321 -2.249932 90)
			(size 0.06985 0.06985)
			(layers "F.Cu" "F.Mask" "F.Paste")
			(net "VR_PVPP_DEF_PHASE")
			(options
				(clearance outline)
				(anchor circle)
			)
			(primitives
				(gr_poly
					(pts
						(arc
							(start -0.2413 0.1397)
							(mid -0.381 0)
							(end -0.2413 -0.1397)
						)
						(xy 0.381 -0.1397) (xy 0.381 0.1397)
					)
					(width 0)
					(fill yes)
				)
			)
		)
		(pad "31" smd custom
			(at 2.249932 -2.8321 90)
			(size 0.06985 0.06985)
			(layers "F.Cu" "F.Mask" "F.Paste")
			(net "VR_PVPP_DEF_PHASE")
			(options
				(clearance outline)
				(anchor circle)
			)
			(primitives
				(gr_poly
					(pts
						(arc
							(start 0.1397 0.2413)
							(mid 0 0.381)
							(end -0.1397 0.2413)
						)
						(xy -0.1397 -0.381) (xy 0.1397 -0.381)
					)
					(width 0)
					(fill yes)
				)
			)
		)
		(pad "32" smd custom
			(at 1.75006 -2.8321 90)
			(size 0.06985 0.06985)
			(layers "F.Cu" "F.Mask" "F.Paste")
			(net "VR_PVPP_DEF_PHASE")
			(options
				(clearance outline)
				(anchor circle)
			)
			(primitives
				(gr_poly
					(pts
						(arc
							(start 0.1397 0.2413)
							(mid 0 0.381)
							(end -0.1397 0.2413)
						)
						(xy -0.1397 -0.381) (xy 0.1397 -0.381)
					)
					(width 0)
					(fill yes)
				)
			)
		)
		(pad "33" smd custom
			(at 1.249934 -2.8321 90)
			(size 0.06985 0.06985)
			(layers "F.Cu" "F.Mask" "F.Paste")
			(net "VR_PVPP_DEF_PHASE")
			(options
				(clearance outline)
				(anchor circle)
			)
			(primitives
				(gr_poly
					(pts
						(arc
							(start 0.1397 0.2413)
							(mid 0 0.381)
							(end -0.1397 0.2413)
						)
						(xy -0.1397 -0.381) (xy 0.1397 -0.381)
					)
					(width 0)
					(fill yes)
				)
			)
		)
		(pad "34" smd custom
			(at 0.750062 -2.8321 90)
			(size 0.06985 0.06985)
			(layers "F.Cu" "F.Mask" "F.Paste")
			(net "VR_PVPP_DEF_PHASE")
			(options
				(clearance outline)
				(anchor circle)
			)
			(primitives
				(gr_poly
					(pts
						(arc
							(start 0.1397 0.2413)
							(mid 0 0.381)
							(end -0.1397 0.2413)
						)
						(xy -0.1397 -0.381) (xy 0.1397 -0.381)
					)
					(width 0)
					(fill yes)
				)
			)
		)
		(pad "35" smd custom
			(at 0.249936 -2.8321 90)
			(size 0.06985 0.06985)
			(layers "F.Cu" "F.Mask" "F.Paste")
			(net "VR_PVPP_DEF_PHASE")
			(options
				(clearance outline)
				(anchor circle)
			)
			(primitives
				(gr_poly
					(pts
						(arc
							(start 0.1397 0.2413)
							(mid 0 0.381)
							(end -0.1397 0.2413)
						)
						(xy -0.1397 -0.381) (xy 0.1397 -0.381)
					)
					(width 0)
					(fill yes)
				)
			)
		)
	)
)
